(kicad_pcb
	(version 20260206)
	(generator "pcbnew")
	(generator_version "10.0")
	(general
		(thickness 1.6)
		(legacy_teardrops no)
	)
	(paper "A4")
	(title_block
		(title "baseboard — 13948-1b.1110WZS1818.brd")
		(comment 1 "Honey Badger (Wiwynn) / footprints 1458-1464 of 2523")
	)
	(layers
		(0 "F.Cu" signal "TOP")
		(4 "In1.Cu" signal "L2GND")
		(6 "In2.Cu" signal "L3")
		(8 "In3.Cu" signal "L4VCC")
		(10 "In4.Cu" signal "L5VCC")
		(12 "In5.Cu" signal "L6")
		(14 "In6.Cu" signal "L7GND")
		(2 "B.Cu" signal "BOTTOM")
		(9 "F.Adhes" user "F.Adhesive")
		(11 "B.Adhes" user "B.Adhesive")
		(13 "F.Paste" user "Package Geometry/Pastemask Top")
		(15 "B.Paste" user "Package Geometry/Pastemask Bottom")
		(5 "F.SilkS" user "Ref Des/Silkscreen Top")
		(7 "B.SilkS" user "Ref Des/Silkscreen Bottom")
		(1 "F.Mask" user "Board Geometry/Soldermask Top")
		(3 "B.Mask" user "Board Geometry/Soldermask Bottom")
		(17 "Dwgs.User" user "User.Drawings")
		(19 "Cmts.User" user "User.Comments")
		(21 "Eco1.User" user "User.Eco1")
		(23 "Eco2.User" user "User.Eco2")
		(25 "Edge.Cuts" user "Board Geometry/Outline")
		(27 "Margin" user)
		(31 "F.CrtYd" user "Package Geometry/Place Bound Top")
		(29 "B.CrtYd" user "Package Geometry/Place Bound Bottom")
		(35 "F.Fab" user "Ref Des/Assembly Top")
		(33 "B.Fab" user "Ref Des/Assembly Bottom")
	)
	(footprint ""
		(layer "F.Cu")
		(at 95.89897 -86.233 90)
		(property "Reference" "SR772"
			(at 0 0 90)
			(layer "F.SilkS")
			(hide yes)
			(effects
				(font
					(size 1.27 1.27)
				)
			)
		)
		(property "Value" "4K75R2F-1-GP"
			(at 0.064008 -3.993896 90)
			(unlocked yes)
			(layer "F.Fab")
			(hide yes)
			(effects
				(font
					(size 1.016 1.016)
					(thickness 0.1524)
				)
			)
		)
		(property "Device Type" "R402H16"
			(at 0.064008 -5.517896 90)
			(unlocked yes)
			(layer "F.Fab")
			(hide yes)
			(effects
				(font
					(size 1.016 1.016)
					(thickness 0.1524)
				)
			)
		)
		(duplicate_pad_numbers_are_jumpers no)
		(fp_line
			(start 0.508 -0.9398)
			(end -0.508 -0.9398)
			(stroke
				(width 0.1524)
				(type default)
			)
			(layer "F.SilkS")
		)
		(fp_line
			(start -0.508 -0.9398)
			(end -0.508 0.9398)
			(stroke
				(width 0.1524)
				(type default)
			)
			(layer "F.SilkS")
		)
		(fp_rect
			(start -0.508 0.9398)
			(end 0.508 -0.9398)
			(stroke
				(width 0)
				(type default)
			)
			(fill no)
			(layer "F.CrtYd")
		)
		(fp_rect
			(start -0.508 0.9398)
			(end 0.508 -0.9398)
			(stroke
				(width 0)
				(type default)
			)
			(fill no)
			(layer "F.Fab")
		)
		(pad "1" smd custom
			(at 0 -0.4445 90)
			(size 0.1397 0.1397)
			(layers "F.Cu" "F.Mask" "F.Paste")
			(net "P1V8_E")
			(options
				(clearance outline)
				(anchor circle)
			)
			(primitives
				(gr_poly
					(pts
						(arc
							(start -0.1778 -0.2794)
							(mid -0.249642 -0.249642)
							(end -0.2794 -0.1778)
						)
						(arc
							(start -0.2794 0.1778)
							(mid -0.249642 0.249642)
							(end -0.1778 0.2794)
						)
						(arc
							(start 0.1778 0.2794)
							(mid 0.249642 0.249642)
							(end 0.2794 0.1778)
						)
						(arc
							(start 0.2794 -0.1778)
							(mid 0.249642 -0.249642)
							(end 0.1778 -0.2794)
						)
					)
					(width 0)
					(fill yes)
				)
			)
		)
		(pad "2" smd custom
			(at 0 0.4445 90)
			(size 0.1397 0.1397)
			(layers "F.Cu" "F.Mask" "F.Paste")
			(net "SXP_ACTIVE_1")
			(options
				(clearance outline)
				(anchor circle)
			)
			(primitives
				(gr_poly
					(pts
						(arc
							(start -0.1778 -0.2794)
							(mid -0.249642 -0.249642)
							(end -0.2794 -0.1778)
						)
						(arc
							(start -0.2794 0.1778)
							(mid -0.249642 0.249642)
							(end -0.1778 0.2794)
						)
						(arc
							(start 0.1778 0.2794)
							(mid 0.249642 0.249642)
							(end 0.2794 0.1778)
						)
						(arc
							(start 0.2794 -0.1778)
							(mid 0.249642 -0.249642)
							(end 0.1778 -0.2794)
						)
					)
					(width 0)
					(fill yes)
				)
			)
		)
	)
	(footprint ""
		(layer "F.Cu")
		(at 174.743872 -196.591936 180)
		(property "Reference" "C246"
			(at 0 0 180)
			(layer "F.SilkS")
			(hide yes)
			(effects
				(font
					(size 1.27 1.27)
				)
			)
		)
		(property "Value" "SC220P50V3JN-GP"
			(at 0 -2.8194 180)
			(unlocked yes)
			(layer "F.Fab")
			(hide yes)
			(effects
				(font
					(size 1.016 1.016)
					(thickness 0.1524)
				)
			)
		)
		(property "Device Type" "C603H36"
			(at 0 -4.3434 180)
			(unlocked yes)
			(layer "F.Fab")
			(hide yes)
			(effects
				(font
					(size 1.016 1.016)
					(thickness 0.1524)
				)
			)
		)
		(duplicate_pad_numbers_are_jumpers no)
		(fp_line
			(start 0.508 0)
			(end -0.508 0)
			(stroke
				(width 0.2032)
				(type default)
			)
			(layer "F.SilkS")
		)
		(fp_rect
			(start -0.5842 1.3335)
			(end 0.5842 -1.3335)
			(stroke
				(width 0)
				(type default)
			)
			(fill no)
			(layer "F.CrtYd")
		)
		(fp_rect
			(start -0.5842 1.3335)
			(end 0.5842 -1.3335)
			(stroke
				(width 0)
				(type default)
			)
			(fill no)
			(layer "F.Fab")
		)
		(pad "1" smd custom
			(at 0 -0.762 180)
			(size 0.2159 0.2159)
			(layers "F.Cu" "F.Mask" "F.Paste")
			(net "BMC_I2C_C_SCL")
			(options
				(clearance outline)
				(anchor circle)
			)
			(primitives
				(gr_poly
					(pts
						(arc
							(start -0.3302 -0.4318)
							(mid -0.402042 -0.402042)
							(end -0.4318 -0.3302)
						)
						(arc
							(start -0.4318 0.3302)
							(mid -0.402042 0.402042)
							(end -0.3302 0.4318)
						)
						(arc
							(start 0.3302 0.4318)
							(mid 0.402042 0.402042)
							(end 0.4318 0.3302)
						)
						(arc
							(start 0.4318 -0.3302)
							(mid 0.402042 -0.402042)
							(end 0.3302 -0.4318)
						)
					)
					(width 0)
					(fill yes)
				)
			)
		)
		(pad "2" smd custom
			(at 0 0.762 180)
			(size 0.2159 0.2159)
			(layers "F.Cu" "F.Mask" "F.Paste")
			(net "GND")
			(options
				(clearance outline)
				(anchor circle)
			)
			(primitives
				(gr_poly
					(pts
						(arc
							(start -0.3302 -0.4318)
							(mid -0.402042 -0.402042)
							(end -0.4318 -0.3302)
						)
						(arc
							(start -0.4318 0.3302)
							(mid -0.402042 0.402042)
							(end -0.3302 0.4318)
						)
						(arc
							(start 0.3302 0.4318)
							(mid 0.402042 0.402042)
							(end 0.4318 0.3302)
						)
						(arc
							(start 0.4318 -0.3302)
							(mid 0.402042 -0.402042)
							(end 0.3302 -0.4318)
						)
					)
					(width 0)
					(fill yes)
				)
			)
		)
	)
	(footprint ""
		(layer "F.Cu")
		(at 278.384 -207.772 180)
		(property "Reference" "C330"
			(at 0 0 180)
			(layer "F.SilkS")
			(hide yes)
			(effects
				(font
					(size 1.27 1.27)
				)
			)
		)
		(property "Value" "SCD1U25V2KX-2-GP"
			(at 1.1811 -2.7051 180)
			(unlocked yes)
			(layer "F.Fab")
			(hide yes)
			(effects
				(font
					(size 1.016 1.016)
					(thickness 0.1524)
				)
			)
		)
		(property "Device Type" "C402H22"
			(at 1.1811 -4.2291 180)
			(unlocked yes)
			(layer "F.Fab")
			(hide yes)
			(effects
				(font
					(size 1.016 1.016)
					(thickness 0.1524)
				)
			)
		)
		(duplicate_pad_numbers_are_jumpers no)
		(fp_rect
			(start -0.4318 0.9525)
			(end 0.4318 -0.9525)
			(stroke
				(width 0)
				(type default)
			)
			(fill no)
			(layer "F.CrtYd")
		)
		(fp_rect
			(start -0.4318 0.9525)
			(end 0.4318 -0.9525)
			(stroke
				(width 0)
				(type default)
			)
			(fill no)
			(layer "F.Fab")
		)
		(pad "1" smd custom
			(at 0 -0.4445 180)
			(size 0.1524 0.1524)
			(layers "F.Cu" "F.Mask" "F.Paste")
			(net "P3V3_STBY")
			(options
				(clearance outline)
				(anchor circle)
			)
			(primitives
				(gr_poly
					(pts
						(arc
							(start 0.3048 -0.2032)
							(mid 0.275042 -0.275042)
							(end 0.2032 -0.3048)
						)
						(arc
							(start -0.2032 -0.3048)
							(mid -0.275042 -0.275042)
							(end -0.3048 -0.2032)
						)
						(arc
							(start -0.3048 0.2032)
							(mid -0.275042 0.275042)
							(end -0.2032 0.3048)
						)
						(arc
							(start 0.2032 0.3048)
							(mid 0.275042 0.275042)
							(end 0.3048 0.2032)
						)
					)
					(width 0)
					(fill yes)
				)
			)
		)
		(pad "2" smd custom
			(at 0 0.4445 180)
			(size 0.1524 0.1524)
			(layers "F.Cu" "F.Mask" "F.Paste")
			(net "GND")
			(options
				(clearance outline)
				(anchor circle)
			)
			(primitives
				(gr_poly
					(pts
						(arc
							(start 0.3048 -0.2032)
							(mid 0.275042 -0.275042)
							(end 0.2032 -0.3048)
						)
						(arc
							(start -0.2032 -0.3048)
							(mid -0.275042 -0.275042)
							(end -0.3048 -0.2032)
						)
						(arc
							(start -0.3048 0.2032)
							(mid -0.275042 0.275042)
							(end -0.2032 0.3048)
						)
						(arc
							(start 0.2032 0.3048)
							(mid 0.275042 0.275042)
							(end 0.3048 0.2032)
						)
					)
					(width 0)
					(fill yes)
				)
			)
		)
	)
	(footprint ""
		(layer "F.Cu")
		(at 279.273 -65.532 180)
		(property "Reference" "C265"
			(at 0 0 180)
			(layer "F.SilkS")
			(hide yes)
			(effects
				(font
					(size 1.27 1.27)
				)
			)
		)
		(property "Value" "SCD047U16V2KX-1-GP"
			(at 1.1811 -2.7051 180)
			(unlocked yes)
			(layer "F.Fab")
			(hide yes)
			(effects
				(font
					(size 1.016 1.016)
					(thickness 0.1524)
				)
			)
		)
		(property "Device Type" "C402H22"
			(at 1.1811 -4.2291 180)
			(unlocked yes)
			(layer "F.Fab")
			(hide yes)
			(effects
				(font
					(size 1.016 1.016)
					(thickness 0.1524)
				)
			)
		)
		(duplicate_pad_numbers_are_jumpers no)
		(fp_rect
			(start -0.4318 0.9525)
			(end 0.4318 -0.9525)
			(stroke
				(width 0)
				(type default)
			)
			(fill no)
			(layer "F.CrtYd")
		)
		(fp_rect
			(start -0.4318 0.9525)
			(end 0.4318 -0.9525)
			(stroke
				(width 0)
				(type default)
			)
			(fill no)
			(layer "F.Fab")
		)
		(pad "1" smd custom
			(at 0 -0.4445 180)
			(size 0.1524 0.1524)
			(layers "F.Cu" "F.Mask" "F.Paste")
			(net "VR_HSC_TIMER_MSB")
			(options
				(clearance outline)
				(anchor circle)
			)
			(primitives
				(gr_poly
					(pts
						(arc
							(start 0.3048 -0.2032)
							(mid 0.275042 -0.275042)
							(end 0.2032 -0.3048)
						)
						(arc
							(start -0.2032 -0.3048)
							(mid -0.275042 -0.275042)
							(end -0.3048 -0.2032)
						)
						(arc
							(start -0.3048 0.2032)
							(mid -0.275042 0.275042)
							(end -0.2032 0.3048)
						)
						(arc
							(start 0.2032 0.3048)
							(mid 0.275042 0.275042)
							(end 0.3048 0.2032)
						)
					)
					(width 0)
					(fill yes)
				)
			)
		)
		(pad "2" smd custom
			(at 0 0.4445 180)
			(size 0.1524 0.1524)
			(layers "F.Cu" "F.Mask" "F.Paste")
			(net "GND")
			(options
				(clearance outline)
				(anchor circle)
			)
			(primitives
				(gr_poly
					(pts
						(arc
							(start 0.3048 -0.2032)
							(mid 0.275042 -0.275042)
							(end 0.2032 -0.3048)
						)
						(arc
							(start -0.2032 -0.3048)
							(mid -0.275042 -0.275042)
							(end -0.3048 -0.2032)
						)
						(arc
							(start -0.3048 0.2032)
							(mid -0.275042 0.275042)
							(end -0.2032 0.3048)
						)
						(arc
							(start 0.2032 0.3048)
							(mid 0.275042 0.275042)
							(end 0.3048 0.2032)
						)
					)
					(width 0)
					(fill yes)
				)
			)
		)
	)
	(footprint ""
		(layer "F.Cu")
		(at 34.036 -172.847 180)
		(property "Reference" "SR1280"
			(at 0 0 180)
			(layer "F.SilkS")
			(hide yes)
			(effects
				(font
					(size 1.27 1.27)
				)
			)
		)
		(property "Value" "10KR2F-2-GP"
			(at 0.064008 -3.993896 180)
			(unlocked yes)
			(layer "F.Fab")
			(hide yes)
			(effects
				(font
					(size 1.016 1.016)
					(thickness 0.1524)
				)
			)
		)
		(property "Device Type" "R402H16"
			(at 0.064008 -5.517896 180)
			(unlocked yes)
			(layer "F.Fab")
			(hide yes)
			(effects
				(font
					(size 1.016 1.016)
					(thickness 0.1524)
				)
			)
		)
		(duplicate_pad_numbers_are_jumpers no)
		(fp_line
			(start 0.508 -0.9398)
			(end -0.508 -0.9398)
			(stroke
				(width 0.1524)
				(type default)
			)
			(layer "F.SilkS")
		)
		(fp_line
			(start -0.508 -0.9398)
			(end -0.508 0.9398)
			(stroke
				(width 0.1524)
				(type default)
			)
			(layer "F.SilkS")
		)
		(fp_rect
			(start -0.508 0.9398)
			(end 0.508 -0.9398)
			(stroke
				(width 0)
				(type default)
			)
			(fill no)
			(layer "F.CrtYd")
		)
		(fp_rect
			(start -0.508 0.9398)
			(end 0.508 -0.9398)
			(stroke
				(width 0)
				(type default)
			)
			(fill no)
			(layer "F.Fab")
		)
		(pad "1" smd custom
			(at 0 -0.4445 180)
			(size 0.1397 0.1397)
			(layers "F.Cu" "F.Mask" "F.Paste")
			(net "P3V3_STBY_R8")
			(options
				(clearance outline)
				(anchor circle)
			)
			(primitives
				(gr_poly
					(pts
						(arc
							(start -0.1778 -0.2794)
							(mid -0.249642 -0.249642)
							(end -0.2794 -0.1778)
						)
						(arc
							(start -0.2794 0.1778)
							(mid -0.249642 0.249642)
							(end -0.1778 0.2794)
						)
						(arc
							(start 0.1778 0.2794)
							(mid 0.249642 0.249642)
							(end 0.2794 0.1778)
						)
						(arc
							(start 0.2794 -0.1778)
							(mid 0.249642 -0.249642)
							(end 0.1778 -0.2794)
						)
					)
					(width 0)
					(fill yes)
				)
			)
		)
		(pad "2" smd custom
			(at 0 0.4445 180)
			(size 0.1397 0.1397)
			(layers "F.Cu" "F.Mask" "F.Paste")
			(net "P3V3_STBY_G8")
			(options
				(clearance outline)
				(anchor circle)
			)
			(primitives
				(gr_poly
					(pts
						(arc
							(start -0.1778 -0.2794)
							(mid -0.249642 -0.249642)
							(end -0.2794 -0.1778)
						)
						(arc
							(start -0.2794 0.1778)
							(mid -0.249642 0.249642)
							(end -0.1778 0.2794)
						)
						(arc
							(start 0.1778 0.2794)
							(mid 0.249642 0.249642)
							(end 0.2794 0.1778)
						)
						(arc
							(start 0.2794 -0.1778)
							(mid 0.249642 -0.249642)
							(end 0.1778 -0.2794)
						)
					)
					(width 0)
					(fill yes)
				)
			)
		)
	)
	(footprint ""
		(layer "F.Cu")
		(at 168.646348 -122.545856 180)
		(property "Reference" "PR164"
			(at 0 0 180)
			(layer "F.SilkS")
			(hide yes)
			(effects
				(font
					(size 1.27 1.27)
				)
			)
		)
		(property "Value" "113KR2F-1-GP"
			(at 0.064008 -3.993896 180)
			(unlocked yes)
			(layer "F.Fab")
			(hide yes)
			(effects
				(font
					(size 1.016 1.016)
					(thickness 0.1524)
				)
			)
		)
		(property "Device Type" "R402H16"
			(at 0.064008 -5.517896 180)
			(unlocked yes)
			(layer "F.Fab")
			(hide yes)
			(effects
				(font
					(size 1.016 1.016)
					(thickness 0.1524)
				)
			)
		)
		(duplicate_pad_numbers_are_jumpers no)
		(fp_line
			(start 0.508 -0.9398)
			(end -0.508 -0.9398)
			(stroke
				(width 0.1524)
				(type default)
			)
			(layer "F.SilkS")
		)
		(fp_line
			(start -0.508 -0.9398)
			(end -0.508 0.9398)
			(stroke
				(width 0.1524)
				(type default)
			)
			(layer "F.SilkS")
		)
		(fp_rect
			(start -0.508 0.9398)
			(end 0.508 -0.9398)
			(stroke
				(width 0)
				(type default)
			)
			(fill no)
			(layer "F.CrtYd")
		)
		(fp_rect
			(start -0.508 0.9398)
			(end 0.508 -0.9398)
			(stroke
				(width 0)
				(type default)
			)
			(fill no)
			(layer "F.Fab")
		)
		(pad "1" smd custom
			(at 0 -0.4445 180)
			(size 0.1397 0.1397)
			(layers "F.Cu" "F.Mask" "F.Paste")
			(net "P0V9_E_TRIP")
			(options
				(clearance outline)
				(anchor circle)
			)
			(primitives
				(gr_poly
					(pts
						(arc
							(start -0.1778 -0.2794)
							(mid -0.249642 -0.249642)
							(end -0.2794 -0.1778)
						)
						(arc
							(start -0.2794 0.1778)
							(mid -0.249642 0.249642)
							(end -0.1778 0.2794)
						)
						(arc
							(start 0.1778 0.2794)
							(mid 0.249642 0.249642)
							(end 0.2794 0.1778)
						)
						(arc
							(start 0.2794 -0.1778)
							(mid 0.249642 -0.249642)
							(end 0.1778 -0.2794)
						)
					)
					(width 0)
					(fill yes)
				)
			)
		)
		(pad "2" smd custom
			(at 0 0.4445 180)
			(size 0.1397 0.1397)
			(layers "F.Cu" "F.Mask" "F.Paste")
			(net "AGND_P0V9_E")
			(options
				(clearance outline)
				(anchor circle)
			)
			(primitives
				(gr_poly
					(pts
						(arc
							(start -0.1778 -0.2794)
							(mid -0.249642 -0.249642)
							(end -0.2794 -0.1778)
						)
						(arc
							(start -0.2794 0.1778)
							(mid -0.249642 0.249642)
							(end -0.1778 0.2794)
						)
						(arc
							(start 0.1778 0.2794)
							(mid 0.249642 0.249642)
							(end 0.2794 0.1778)
						)
						(arc
							(start 0.2794 -0.1778)
							(mid 0.249642 -0.249642)
							(end 0.1778 -0.2794)
						)
					)
					(width 0)
					(fill yes)
				)
			)
		)
	)
	(footprint ""
		(layer "F.Cu")
		(at 88.27897 -112.014 180)
		(property "Reference" "SC1237"
			(at 0 0 180)
			(layer "F.SilkS")
			(hide yes)
			(effects
				(font
					(size 1.27 1.27)
				)
			)
		)
		(property "Value" "SCD1U6D3V1KX-GP"
			(at -2.8321 -1.7399 180)
			(unlocked yes)
			(layer "F.Fab")
			(hide yes)
			(effects
				(font
					(size 1.016 1.016)
					(thickness 0.1524)
				)
			)
		)
		(property "Device Type" "C0201H13"
			(at -2.8321 -3.2639 180)
			(unlocked yes)
			(layer "F.Fab")
			(hide yes)
			(effects
				(font
					(size 1.016 1.016)
					(thickness 0.1524)
				)
			)
		)
		(duplicate_pad_numbers_are_jumpers no)
		(fp_rect
			(start -0.2794 0.6477)
			(end 0.2794 -0.6477)
			(stroke
				(width 0)
				(type default)
			)
			(fill no)
			(layer "F.CrtYd")
		)
		(fp_rect
			(start -0.2794 0.6477)
			(end 0.2794 -0.6477)
			(stroke
				(width 0)
				(type default)
			)
			(fill no)
			(layer "F.Fab")
		)
		(pad "1" smd custom
			(at 0 -0.2794 180)
			(size 0.0762 0.0762)
			(layers "F.Cu" "F.Mask" "F.Paste")
			(net "P1V8_E")
			(options
				(clearance outline)
				(anchor circle)
			)
			(primitives
				(gr_poly
					(pts
						(arc
							(start 0.1524 -0.127)
							(mid 0.137521 -0.162921)
							(end 0.1016 -0.1778)
						)
						(arc
							(start -0.1016 -0.1778)
							(mid -0.137521 -0.162921)
							(end -0.1524 -0.127)
						)
						(arc
							(start -0.1524 0.127)
							(mid -0.137521 0.162921)
							(end -0.1016 0.1778)
						)
						(arc
							(start 0.1016 0.1778)
							(mid 0.137521 0.162921)
							(end 0.1524 0.127)
						)
					)
					(width 0)
					(fill yes)
				)
			)
		)
		(pad "2" smd custom
			(at 0 0.2794 180)
			(size 0.0762 0.0762)
			(layers "F.Cu" "F.Mask" "F.Paste")
			(net "GND")
			(options
				(clearance outline)
				(anchor circle)
			)
			(primitives
				(gr_poly
					(pts
						(arc
							(start 0.1524 -0.127)
							(mid 0.137521 -0.162921)
							(end 0.1016 -0.1778)
						)
						(arc
							(start -0.1016 -0.1778)
							(mid -0.137521 -0.162921)
							(end -0.1524 -0.127)
						)
						(arc
							(start -0.1524 0.127)
							(mid -0.137521 0.162921)
							(end -0.1016 0.1778)
						)
						(arc
							(start 0.1016 0.1778)
							(mid 0.137521 0.162921)
							(end 0.1524 0.127)
						)
					)
					(width 0)
					(fill yes)
				)
			)
		)
	)
)
